# T6G (Grand Teton) — schematic parts with pin connectivity, parts 2598–2598 of 8303; source: Cadence DE-HDL packaged netlist (pstxprt.dat, pstxnet.dat, pstchip.dat)

J16  SCONN288_DDR506112002KQ  IO  pkg DDR288S_1-1VXC  page 92
  1  VIN_BULK0  POWER  = P12V_MEM_CPU0
  2  RFU0  TRI  = NC
  3  VIN_MGMT  POWER  = P3V3_AUX
  4  HSCL  IN  = I3C_SPD_DDRG_CPU0_SCL
  5  HSDA  BI  = I3C_SPD_DDRG_CPU0_SDA
  6  VSS0  POWER  = GND
  7  DQ0_A  BI  = M_G_CPU0_SA_DQ<0>
  8  VSS1  POWER  = GND
  9  DQ1_A  BI  = M_G_CPU0_SA_DQ<1>
  10  VSS2  POWER  = GND
  11  DQS0_A_T  BI  = M_G_CPU0_SA_DQS_DP<0>
  12  DQS0_A_C  BI  = M_G_CPU0_SA_DQS_DN<0>
  13  VSS3  POWER  = GND
  14  DQ4_A  BI  = M_G_CPU0_SA_DQ<4>
  15  VSS4  POWER  = GND
  16  DQ5_A  BI  = M_G_CPU0_SA_DQ<5>
  17  VSS5  POWER  = GND
  18  DQ8_A  BI  = M_G_CPU0_SA_DQ<8>
  19  VSS6  POWER  = GND
  20  DQ9_A  BI  = M_G_CPU0_SA_DQ<9>
  21  VSS7  POWER  = GND
  22  DQS1_A_T  BI  = M_G_CPU0_SA_DQS_DP<1>
  23  DQS1_A_C  BI  = M_G_CPU0_SA_DQS_DN<1>
  24  VSS8  POWER  = GND
  25  DQ12_A  BI  = M_G_CPU0_SA_DQ<12>
  26  VSS9  POWER  = GND
  27  DQ13_A  BI  = M_G_CPU0_SA_DQ<13>
  28  VSS10  POWER  = GND
  29  DQ16_A  BI  = M_G_CPU0_SA_DQ<16>
  30  VSS11  POWER  = GND
  31  DQ17_A  BI  = M_G_CPU0_SA_DQ<17>
  32  VSS12  POWER  = GND
  33  DQS2_A_T  BI  = M_G_CPU0_SA_DQS_DP<2>
  34  DQS2_A_C  BI  = M_G_CPU0_SA_DQS_DN<2>
  35  VSS13  POWER  = GND
  36  DQ20_A  BI  = M_G_CPU0_SA_DQ<20>
  37  VSS14  POWER  = GND
  38  DQ21_A  BI  = M_G_CPU0_SA_DQ<21>
  39  VSS15  POWER  = GND
  40  DQ24_A  BI  = M_G_CPU0_SA_DQ<24>
  41  VSS16  POWER  = GND
  42  DQ25_A  BI  = M_G_CPU0_SA_DQ<25>
  43  VSS17  POWER  = GND
  44  DQS3_A_T  BI  = M_G_CPU0_SA_DQS_DP<3>
  45  DQS3_A_C  BI  = M_G_CPU0_SA_DQS_DN<3>
  46  VSS18  POWER  = GND
  47  DQ28_A  BI  = M_G_CPU0_SA_DQ<28>
  48  VSS19  POWER  = GND
  49  DQ29_A  BI  = M_G_CPU0_SA_DQ<29>
  50  VSS20  POWER  = GND
  51  CB0_A  BI  = M_G_CPU0_SA_CB<0>
  52  VSS21  POWER  = GND
  53  CB1_A  BI  = M_G_CPU0_SA_CB<1>
  54  VSS22  POWER  = GND
  55  DQS4_A_T  BI  = M_G_CPU0_SA_DQS_DP<4>
  56  DQS4_A_C  BI  = M_G_CPU0_SA_DQS_DN<4>
  57  VSS23  POWER  = GND
  58  CB4_A  BI  = M_G_CPU0_SA_CB<4>
  59  VSS24  POWER  = GND
  60  CB5_A  BI  = M_G_CPU0_SA_CB<5>
  61  VSS25  POWER  = GND
  62  ALERT_N  OUT  = M_G_CPU0_ALERT_N
  63  VSS26  POWER  = GND
  64  CS0_A_N  IN  = M_G_CPU0_SA_CS_N<0>
  65  VSS27  POWER  = GND
  66  CA0_A  IN  = M_G_CPU0_SA_CA<0>
  67  VSS28  POWER  = GND
  68  CA2_A  IN  = M_G_CPU0_SA_CA<2>
  69  VSS29  POWER  = GND
  70  CA4_A  IN  = M_G_CPU0_SA_CA<4>
  71  VSS30  POWER  = GND
  72  CA6_A  IN  = M_G_CPU0_SA_CA<6>
  73  VSS31  POWER  = GND
  74  PAR_A  IN  = M_G_CPU0_SA_PAR
  75  VSS32  POWER  = GND
  76  CA0_B  IN  = M_G_CPU0_SB_CA<0>
  77  VSS33  POWER  = GND
  78  CA2_B  IN  = M_G_CPU0_SB_CA<2>
  79  VSS34  POWER  = GND
  80  CA4_B  IN  = M_G_CPU0_SB_CA<4>
  81  VSS35  POWER  = GND
  82  CA6_B  IN  = M_G_CPU0_SB_CA<6>
  83  VSS36  POWER  = GND
  84  CS0_B_N  IN  = M_G_CPU0_SB_CS_N<0>
  85  VSS37  POWER  = GND
  86  \lbd||rsp_a_n\  OUT  = M_G_CPU0_SA_RSP<0>
  87  \lbs||rsp_b_n\  OUT  = M_G_CPU0_SB_RSP<0>
  88  VSS38  POWER  = GND
  89  CB4_B  BI  = M_G_CPU0_SB_CB<4>
  90  VSS39  POWER  = GND
  91  CB5_B  BI  = M_G_CPU0_SB_CB<5>
  92  VSS40  POWER  = GND
  93  \dqs9_b_t||tdqs9_b_t||dbi4_b_n\  BI  = M_G_CPU0_SB_DQS_DP<9>
  94  \dqs9_b_c||tdqs9_b_c\  BI  = M_G_CPU0_SB_DQS_DN<9>
  95  VSS41  POWER  = GND
  96  CB0_B  BI  = M_G_CPU0_SB_CB<0>
  97  VSS42  POWER  = GND
  98  CB1_B  BI  = M_G_CPU0_SB_CB<1>
  99  VSS43  POWER  = GND
  100  DQ0_B  BI  = M_G_CPU0_SB_DQ<0>
  101  VSS44  POWER  = GND
  102  DQ1_B  BI  = M_G_CPU0_SB_DQ<1>
  103  VSS45  POWER  = GND
  104  DQS0_B_T  BI  = M_G_CPU0_SB_DQS_DP<0>
  105  DQS0_B_C  BI  = M_G_CPU0_SB_DQS_DN<0>
  106  VSS46  POWER  = GND
  107  DQ4_B  BI  = M_G_CPU0_SB_DQ<4>
  108  VSS47  POWER  = GND
  109  DQ5_B  BI  = M_G_CPU0_SB_DQ<5>
  110  VSS48  POWER  = GND
  111  DQ8_B  BI  = M_G_CPU0_SB_DQ<8>
  112  VSS49  POWER  = GND
  113  DQ9_B  BI  = M_G_CPU0_SB_DQ<9>
  114  VSS50  POWER  = GND
  115  DQS1_B_T  BI  = M_G_CPU0_SB_DQS_DP<1>
  116  DQS1_B_C  BI  = M_G_CPU0_SB_DQS_DN<1>
  117  VSS51  POWER  = GND
  118  DQ12_B  BI  = M_G_CPU0_SB_DQ<12>
  119  VSS52  POWER  = GND
  120  DQ13_B  BI  = M_G_CPU0_SB_DQ<13>
  121  VSS53  POWER  = GND
  122  DQ16_B  BI  = M_G_CPU0_SB_DQ<16>
  123  VSS54  POWER  = GND
  124  DQ17_B  BI  = M_G_CPU0_SB_DQ<17>
  125  VSS55  POWER  = GND
  126  DQS2_B_T  BI  = M_G_CPU0_SB_DQS_DP<2>
  127  DQS2_B_C  BI  = M_G_CPU0_SB_DQS_DN<2>
  128  VSS56  POWER  = GND
  129  DQ20_B  BI  = M_G_CPU0_SB_DQ<20>
  130  VSS57  POWER  = GND
  131  DQ21_B  BI  = M_G_CPU0_SB_DQ<21>
  132  VSS58  POWER  = GND
  133  DQ24_B  BI  = M_G_CPU0_SB_DQ<24>
  134  VSS59  POWER  = GND
  135  DQ25_B  BI  = M_G_CPU0_SB_DQ<25>
  136  VSS60  POWER  = GND
  137  DQS3_B_T  BI  = M_G_CPU0_SB_DQS_DP<3>
  138  DQS3_B_C  BI  = M_G_CPU0_SB_DQS_DN<3>
  139  VSS61  POWER  = GND
  140  DQ28_B  BI  = M_G_CPU0_SB_DQ<28>
  141  VSS62  POWER  = GND
  142  DQ29_B  BI  = M_G_CPU0_SB_DQ<29>
  143  VSS63  POWER  = GND
  144  RFU1  TRI  = NC
  145  VIN_BULK1  POWER  = P12V_MEM_CPU0
  146  VIN_BULK2  POWER  = P12V_MEM_CPU0
  147  \pwr_good||fail_n\  BI  = PWRGD_CHG_CPU0_DIMM0
  148  HAS  IN  = PD_CHG_CPU0_DIMM0_SAA
  149  RFU2  TRI  = NC
  150  RFU3  TRI  = NC
  151  VSS64  POWER  = GND
  152  DQ2_A  BI  = M_G_CPU0_SA_DQ<2>
  153  VSS65  POWER  = GND
  154  DQ3_A  BI  = M_G_CPU0_SA_DQ<3>
  155  VSS66  POWER  = GND
  156  \dqs5_a_c||tdqs5_a_c||dqs5_a_t||tdqs5_a_t\  BI  = M_G_CPU0_SA_DQS_DN<5>
  157  \dqs5_a_t||tdqs5_a_t\  BI  = M_G_CPU0_SA_DQS_DP<5>
  158  VSS67  POWER  = GND
  159  DQ6_A  BI  = M_G_CPU0_SA_DQ<6>
  160  VSS68  POWER  = GND
  161  DQ7_A  BI  = M_G_CPU0_SA_DQ<7>
  162  VSS69  POWER  = GND
  163  DQ10_A  BI  = M_G_CPU0_SA_DQ<10>
  164  VSS70  POWER  = GND
  165  DQ11_A  BI  = M_G_CPU0_SA_DQ<11>
  166  VSS71  POWER  = GND
  167  \dqs6_a_c||tdqs6_a_c||dqs6_a_t||tdqs6_a_t\  BI  = M_G_CPU0_SA_DQS_DN<6>
  168  \dqs6_a_t||tdqs6_a_t\  BI  = M_G_CPU0_SA_DQS_DP<6>
  169  VSS72  POWER  = GND
  170  DQ14_A  BI  = M_G_CPU0_SA_DQ<14>
  171  VSS73  POWER  = GND
  172  DQ15_A  BI  = M_G_CPU0_SA_DQ<15>
  173  VSS74  POWER  = GND
  174  DQ18_A  BI  = M_G_CPU0_SA_DQ<18>
  175  VSS75  POWER  = GND
  176  DQ19_A  BI  = M_G_CPU0_SA_DQ<19>
  177  VSS76  POWER  = GND
  178  \dqs7_a_c||tdqs7_a_c\  BI  = M_G_CPU0_SA_DQS_DN<7>
  179  \dqs7_a_t||tdqs7_a_t\  BI  = M_G_CPU0_SA_DQS_DP<7>
  180  VSS77  POWER  = GND
  181  DQ22_A  BI  = M_G_CPU0_SA_DQ<22>
  182  VSS78  POWER  = GND
  183  DQ23_A  BI  = M_G_CPU0_SA_DQ<23>
  184  VSS79  POWER  = GND
  185  DQ26_A  BI  = M_G_CPU0_SA_DQ<26>
  186  VSS80  POWER  = GND
  187  DQ27_A  BI  = M_G_CPU0_SA_DQ<27>
  188  VSS81  POWER  = GND
  189  \dqs8_a_c||tdqs8_a_c\  BI  = M_G_CPU0_SA_DQS_DN<8>
  190  \dqs8_a_t||tdqs8_a_t\  BI  = M_G_CPU0_SA_DQS_DP<8>
  191  VSS82  POWER  = GND
  192  DQ30_A  BI  = M_G_CPU0_SA_DQ<30>
  193  VSS83  POWER  = GND
  194  DQ31_A  BI  = M_G_CPU0_SA_DQ<31>
  195  VSS84  POWER  = GND
  196  CB2_A  BI  = M_G_CPU0_SA_CB<2>
  197  VSS85  POWER  = GND
  198  CB3_A  BI  = M_G_CPU0_SA_CB<3>
  199  VSS86  POWER  = GND
  200  \dqs9_a_c||tdqs9_a_c\  BI  = M_G_CPU0_SA_DQS_DN<9>
  201  \dqs9_a_t||tdqs9_a_t\  BI  = M_G_CPU0_SA_DQS_DP<9>
  202  VSS87  POWER  = GND
  203  CB6_A  BI  = M_G_CPU0_SA_CB<6>
  204  VSS88  POWER  = GND
  205  CB7_A  BI  = M_G_CPU0_SA_CB<7>
  206  VSS89  POWER  = GND
  207  RESET_N  IN  = M_G_CPU0_RESET_N
  208  VSS90  POWER  = GND
  209  CS1_A_N  IN  = M_G_CPU0_SA_CS_N<1>
  210  VSS91  POWER  = GND
  211  CA1_A  IN  = M_G_CPU0_SA_CA<1>
  212  VSS92  POWER  = GND
  213  CA3_A  IN  = M_G_CPU0_SA_CA<3>
  214  VSS93  POWER  = GND
  215  CA5_A  IN  = M_G_CPU0_SA_CA<5>
  216  VSS94  POWER  = GND
  217  CK_T  IN  = M_G_CPU0_CLK_DP<0>
  218  CK_C  IN  = M_G_CPU0_CLK_DN<0>
  219  VSS95  POWER  = GND
  220  RFU4  TRI  = NC
  221  CA1_B  IN  = M_G_CPU0_SB_CA<1>
  222  VSS96  POWER  = GND
  223  CA3_B  IN  = M_G_CPU0_SB_CA<3>
  224  VSS97  POWER  = GND
  225  CA5_B  IN  = M_G_CPU0_SB_CA<5>
  226  VSS98  POWER  = GND
  227  PAR_B  IN  = M_G_CPU0_SB_PAR
  228  VSS99  POWER  = GND
  229  CS1_B_N  IN  = M_G_CPU0_SB_CS_N<1>
  230  VSS100  POWER  = GND
  231  RFU5  TRI  = NC
  232  RFU6  TRI  = NC
  233  VSS101  POWER  = GND
  234  CB6_B  BI  = M_G_CPU0_SB_CB<6>
  235  VSS102  POWER  = GND
  236  CB7_B  BI  = M_G_CPU0_SB_CB<7>
  237  VSS103  POWER  = GND
  238  DQS4_B_C  BI  = M_G_CPU0_SB_DQS_DN<4>
  239  DQS4_B_T  BI  = M_G_CPU0_SB_DQS_DP<4>
  240  VSS104  POWER  = GND
  241  CB2_B  BI  = M_G_CPU0_SB_CB<2>
  242  VSS105  POWER  = GND
  243  CB3_B  BI  = M_G_CPU0_SB_CB<3>
  244  VSS106  POWER  = GND
  245  DQ2_B  BI  = M_G_CPU0_SB_DQ<2>
  246  VSS107  POWER  = GND
  247  DQ3_B  BI  = M_G_CPU0_SB_DQ<3>
  248  VSS108  POWER  = GND
  249  \dqs5_b_c||tdqs5_b_c\  BI  = M_G_CPU0_SB_DQS_DN<5>
  250  \dqs5_b_t||tdqs5_b_t\  BI  = M_G_CPU0_SB_DQS_DP<5>
  251  VSS109  POWER  = GND
  252  DQ6_B  BI  = M_G_CPU0_SB_DQ<6>
  253  VSS110  POWER  = GND
  254  DQ7_B  BI  = M_G_CPU0_SB_DQ<7>
  255  VSS111  POWER  = GND
  256  DQ10_B  BI  = M_G_CPU0_SB_DQ<10>
  257  VSS112  POWER  = GND
  258  DQ11_B  BI  = M_G_CPU0_SB_DQ<11>
  259  VSS113  POWER  = GND
  260  \dqs6_b_c||tdqs6_b_c\  BI  = M_G_CPU0_SB_DQS_DN<6>
  261  \dqs6_b_t||tdqs6_b_t\  BI  = M_G_CPU0_SB_DQS_DP<6>
  262  VSS114  POWER  = GND
  263  DQ14_B  BI  = M_G_CPU0_SB_DQ<14>
  264  VSS115  POWER  = GND
  265  DQ15_B  BI  = M_G_CPU0_SB_DQ<15>
  266  VSS116  POWER  = GND
  267  DQ18_B  BI  = M_G_CPU0_SB_DQ<18>
  268  VSS117  POWER  = GND
  269  DQ19_B  BI  = M_G_CPU0_SB_DQ<19>
  270  VSS118  POWER  = GND
  271  \dqs7_b_c||tdqs7_b_c\  BI  = M_G_CPU0_SB_DQS_DN<7>
  272  \dqs7_b_t||tdqs7_b_t\  BI  = M_G_CPU0_SB_DQS_DP<7>
  273  VSS119  POWER  = GND
  274  DQ22_B  BI  = M_G_CPU0_SB_DQ<22>
  275  VSS120  POWER  = GND
  276  DQ23_B  BI  = M_G_CPU0_SB_DQ<23>
  277  VSS121  POWER  = GND
  278  DQ26_B  BI  = M_G_CPU0_SB_DQ<26>
  279  VSS122  POWER  = GND
  280  DQ27_B  BI  = M_G_CPU0_SB_DQ<27>
  281  VSS123  POWER  = GND
  282  \dqs8_b_c||tdqs8_b_c\  BI  = M_G_CPU0_SB_DQS_DN<8>
  283  \dqs8_b_t||tdqs8_b_t\  BI  = M_G_CPU0_SB_DQS_DP<8>
  284  VSS124  POWER  = GND
  285  DQ30_B  BI  = M_G_CPU0_SB_DQ<30>
  286  VSS125  POWER  = GND
  287  DQ31_B  BI  = M_G_CPU0_SB_DQ<31>
  288  VSS126  POWER  = GND
  G1  G1  POWER  = GND
  G2  G2  POWER  = GND
  G3  G3  POWER  = GND
